G04*
G04 #@! TF.GenerationSoftware,Altium Limited,Altium Designer,22.4.2 (48)*
G04*
G04 Layer_Color=16711935*
%FSLAX25Y25*%
%MOIN*%
G70*
G04*
G04 #@! TF.SameCoordinates,446674BB-F454-490D-8607-5140536C8ADF*
G04*
G04*
G04 #@! TF.FilePolarity,Positive*
G04*
G01*
G75*
%ADD14C,0.00394*%
D14*
X148622Y-372195D02*
G03*
X134252Y-372195I-7185J0D01*
G01*
X200197Y-385876D02*
G03*
X192717Y-385876I-3740J0D01*
G01*
X200197D02*
G03*
X192717Y-385876I-3740J0D01*
G01*
X148622Y-372195D02*
G03*
X134252Y-372195I-7185J0D01*
G01*
X283661Y-365009D02*
X700787D01*
X-28543Y22392D02*
X700787D01*
X700787Y-365009D01*
X-28543Y-397490D02*
Y22392D01*
Y-397490D02*
X30512D01*
Y-365009D01*
X102756D01*
Y-397490D02*
Y-365009D01*
Y-397490D02*
X134252D01*
Y-372195D01*
X148622Y-413238D02*
Y-372195D01*
X150591Y-415206D02*
X190748D01*
X202165D02*
X281693D01*
X283661Y-413238D02*
Y-365009D01*
X148622Y-413238D02*
X150591Y-415206D01*
X190748D02*
X192717Y-413238D01*
X200197D02*
X202165Y-415206D01*
X281693D02*
X283661Y-413238D01*
X192717D02*
Y-385876D01*
X200197Y-413238D02*
Y-385876D01*
M02*
